(kicad_pcb
	(version 20241229)
	(generator "pcbnew")
	(generator_version "9.0")
	(general
		(thickness 1.294)
		(legacy_teardrops no)
	)
	(paper "A3")
	(title_block
		(title "Kintex 410T devboard")
		(date "2024-04-03")
		(rev "1.1.2")
		(comment 9 "footprints 731-735 of 975")
	)
	(layers
		(0 "F.Cu" mixed)
		(4 "In1.Cu" power)
		(6 "In2.Cu" power)
		(8 "In3.Cu" mixed)
		(10 "In4.Cu" power)
		(12 "In5.Cu" mixed)
		(14 "In6.Cu" power)
		(16 "In7.Cu" mixed)
		(18 "In8.Cu" power)
		(2 "B.Cu" mixed)
		(9 "F.Adhes" user "F.Adhesive")
		(11 "B.Adhes" user "B.Adhesive")
		(13 "F.Paste" user)
		(15 "B.Paste" user)
		(5 "F.SilkS" user "F.Silkscreen")
		(7 "B.SilkS" user "B.Silkscreen")
		(1 "F.Mask" user)
		(3 "B.Mask" user)
		(17 "Dwgs.User" user "User.Drawings")
		(19 "Cmts.User" user "User.Comments")
		(21 "Eco1.User" user "User.Eco1")
		(23 "Eco2.User" user "User.Eco2")
		(25 "Edge.Cuts" user)
		(27 "Margin" user)
		(31 "F.CrtYd" user "F.Courtyard")
		(29 "B.CrtYd" user "B.Courtyard")
		(35 "F.Fab" user)
		(33 "B.Fab" user)
	)
	(footprint "antmicro-footprints:C_0402_1005Metric"
		(layer "B.Cu")
		(at 197 124.5 180)
		(descr "Capacitor SMD 0402")
		(tags "capacitor SMD 0402")
		(property "Reference" "C68"
			(at -25.1 29.6 0)
			(layer "B.SilkS")
			(effects
				(font
					(size 0.7 0.7)
					(thickness 0.15)
				)
				(justify left bottom mirror)
			)
		)
		(property "Value" "C_100n_0402"
			(at 0 -1.169 0)
			(layer "B.Fab")
			(effects
				(font
					(size 0.7 0.7)
					(thickness 0.15)
				)
				(justify left bottom mirror)
			)
		)
		(property "Description" "SMD Multilayer Ceramic Capacitor, 0.1 µF, 50 V, 0402 [1005 Metric], ± 10%, X5R, GRM Series"
			(at 0 0 180)
			(layer "F.Fab")
			(hide yes)
			(effects
				(font
					(size 1.27 1.27)
					(thickness 0.15)
				)
			)
		)
		(property "Author" "Antmicro"
			(at 394 249 0)
			(layer "B.Fab")
			(hide yes)
			(effects
				(font
					(size 1 1)
					(thickness 0.15)
				)
				(justify mirror)
			)
		)
		(property "Dielectric" "X5R"
			(at 394 249 0)
			(layer "B.Fab")
			(hide yes)
			(effects
				(font
					(size 1 1)
					(thickness 0.15)
				)
				(justify mirror)
			)
		)
		(property "License" "Apache-2.0"
			(at 394 249 0)
			(layer "B.Fab")
			(hide yes)
			(effects
				(font
					(size 1 1)
					(thickness 0.15)
				)
				(justify mirror)
			)
		)
		(property "MPN" "GRM155R61H104KE14D"
			(at 394 249 0)
			(layer "B.Fab")
			(hide yes)
			(effects
				(font
					(size 1 1)
					(thickness 0.15)
				)
				(justify mirror)
			)
		)
		(property "Manufacturer" "Murata"
			(at 394 249 0)
			(layer "B.Fab")
			(hide yes)
			(effects
				(font
					(size 1 1)
					(thickness 0.15)
				)
				(justify mirror)
			)
		)
		(property "Val" "100n"
			(at 394 249 0)
			(layer "B.Fab")
			(hide yes)
			(effects
				(font
					(size 1 1)
					(thickness 0.15)
				)
				(justify mirror)
			)
		)
		(property "Voltage" "50V"
			(at 394 249 0)
			(layer "B.Fab")
			(hide yes)
			(effects
				(font
					(size 1 1)
					(thickness 0.15)
				)
				(justify mirror)
			)
		)
		(sheetname "FPGA Bank 18 & 32")
		(sheetfile "fpga-bank-18-32.kicad_sch")
		(attr smd)
		(fp_rect
			(start -0.925 0.47)
			(end 0.925 -0.47)
			(stroke
				(width 0.05)
				(type default)
			)
			(fill no)
			(layer "B.CrtYd")
		)
		(fp_line
			(start 0.504 0.25)
			(end 0.504 -0.248)
			(stroke
				(width 0.15)
				(type solid)
			)
			(layer "B.Fab")
		)
		(fp_line
			(start 0.504 -0.248)
			(end -0.494 -0.248)
			(stroke
				(width 0.15)
				(type solid)
			)
			(layer "B.Fab")
		)
		(fp_line
			(start -0.494 0.25)
			(end 0.504 0.25)
			(stroke
				(width 0.15)
				(type solid)
			)
			(layer "B.Fab")
		)
		(fp_line
			(start -0.494 -0.248)
			(end -0.494 0.25)
			(stroke
				(width 0.15)
				(type solid)
			)
			(layer "B.Fab")
		)
		(pad "1" smd roundrect
			(at -0.48 0 180)
			(size 0.59 0.64)
			(layers "B.Cu" "B.Mask" "B.Paste")
			(roundrect_rratio 0.25)
			(net 1 "GND")
			(pintype "passive")
		)
		(pad "2" smd roundrect
			(at 0.48 0 180)
			(size 0.59 0.64)
			(layers "B.Cu" "B.Mask" "B.Paste")
			(roundrect_rratio 0.25)
			(net 24 "+3V3")
			(pintype "passive")
		)
	)
	(footprint "antmicro-footprints:R_0402_1005Metric"
		(layer "B.Cu")
		(at 254.801 170.9 -90)
		(descr "Resistor SMD 0402")
		(tags "resistor SMD 0402")
		(property "Reference" "R39"
			(at -2.95 -0.074 90)
			(layer "B.SilkS")
			(effects
				(font
					(size 0.7 0.7)
					(thickness 0.15)
				)
				(justify left bottom mirror)
			)
		)
		(property "Value" "R_0R_0402"
			(at 0 -1.4 90)
			(layer "B.Fab")
			(effects
				(font
					(size 0.7 0.7)
					(thickness 0.15)
				)
				(justify left bottom mirror)
			)
		)
		(property "Description" "SMD Chip Resistor, Jumper, 0 ohm, 100 mW, 0402 [1005 Metric], Thick Film, General Purpose"
			(at 0 0 270)
			(layer "F.Fab")
			(hide yes)
			(effects
				(font
					(size 1.27 1.27)
					(thickness 0.15)
				)
			)
		)
		(property "Author" "Antmicro"
			(at 83.901 425.701 0)
			(layer "B.Fab")
			(hide yes)
			(effects
				(font
					(size 1 1)
					(thickness 0.15)
				)
				(justify mirror)
			)
		)
		(property "Current" "1A"
			(at 83.901 425.701 0)
			(layer "B.Fab")
			(hide yes)
			(effects
				(font
					(size 1 1)
					(thickness 0.15)
				)
				(justify mirror)
			)
		)
		(property "DNP" "DNP"
			(at 83.901 425.701 0)
			(layer "B.Fab")
			(hide yes)
			(effects
				(font
					(size 1 1)
					(thickness 0.15)
				)
				(justify mirror)
			)
		)
		(property "License" "Apache-2.0"
			(at 83.901 425.701 0)
			(layer "B.Fab")
			(hide yes)
			(effects
				(font
					(size 1 1)
					(thickness 0.15)
				)
				(justify mirror)
			)
		)
		(property "MPN" "ERJ2GE0R00X"
			(at 83.901 425.701 0)
			(layer "B.Fab")
			(hide yes)
			(effects
				(font
					(size 1 1)
					(thickness 0.15)
				)
				(justify mirror)
			)
		)
		(property "Manufacturer" "Panasonic"
			(at 83.901 425.701 0)
			(layer "B.Fab")
			(hide yes)
			(effects
				(font
					(size 1 1)
					(thickness 0.15)
				)
				(justify mirror)
			)
		)
		(property "Tolerance" ""
			(at 83.901 425.701 0)
			(layer "B.Fab")
			(hide yes)
			(effects
				(font
					(size 1 1)
					(thickness 0.15)
				)
				(justify mirror)
			)
		)
		(property "Val" "0R"
			(at 83.901 425.701 0)
			(layer "B.Fab")
			(hide yes)
			(effects
				(font
					(size 1 1)
					(thickness 0.15)
				)
				(justify mirror)
			)
		)
		(property "dnp" ""
			(at 83.901 425.701 0)
			(layer "B.Fab")
			(hide yes)
			(effects
				(font
					(size 1 1)
					(thickness 0.15)
				)
				(justify mirror)
			)
		)
		(property "exclude_from_bom" ""
			(at 83.901 425.701 0)
			(layer "B.Fab")
			(hide yes)
			(effects
				(font
					(size 1 1)
					(thickness 0.15)
				)
				(justify mirror)
			)
		)
		(sheetname "Power supply")
		(sheetfile "power-supply.kicad_sch")
		(attr smd exclude_from_bom)
		(fp_rect
			(start -0.925 0.47)
			(end 0.925 -0.47)
			(stroke
				(width 0.05)
				(type default)
			)
			(fill no)
			(layer "B.CrtYd")
		)
		(fp_rect
			(start -0.5 0.25)
			(end 0.5 -0.25)
			(stroke
				(width 0.15)
				(type solid)
			)
			(fill no)
			(layer "B.Fab")
		)
		(pad "1" smd roundrect
			(at -0.48 0 270)
			(size 0.59 0.64)
			(layers "B.Cu" "B.Mask" "B.Paste")
			(roundrect_rratio 0.25)
			(net 889 "/Power supply/PG")
			(pintype "passive")
		)
		(pad "2" smd roundrect
			(at 0.48 0 270)
			(size 0.59 0.64)
			(layers "B.Cu" "B.Mask" "B.Paste")
			(roundrect_rratio 0.25)
			(net 798 "/Power supply/POE_ACTIVE")
			(pintype "passive")
		)
	)
	(footprint "antmicro-footprints:C_0201"
		(layer "B.Cu")
		(at 186.730001 117.730001 -45)
		(descr "Capacitor SMD 0201")
		(tags "capacitor SMD 0201")
		(property "Reference" "C163"
			(at -0.625791 0.901561 180)
			(layer "B.SilkS")
			(effects
				(font
					(size 0.7 0.7)
					(thickness 0.15)
				)
				(justify left bottom mirror)
			)
		)
		(property "Value" "C_4u7_0201"
			(at 0 -1.399999 135)
			(layer "B.Fab")
			(effects
				(font
					(size 0.7 0.7)
					(thickness 0.15)
				)
				(justify left bottom mirror)
			)
		)
		(property "Description" "SMD Multilayer Ceramic Capacitor, 4.7 µF, 6.3 V, 0201 [0603 Metric], ± 20%, X5R, GRM Series"
			(at 0 0 315)
			(layer "F.Fab")
			(hide yes)
			(effects
				(font
					(size 1.27 1.27)
					(thickness 0.15)
				)
			)
		)
		(property "Author" "Antmicro"
			(at -28.555731 166.520369 0)
			(layer "B.Fab")
			(hide yes)
			(effects
				(font
					(size 1 1)
					(thickness 0.15)
				)
				(justify mirror)
			)
		)
		(property "Dielectric" ""
			(at -28.555731 166.520369 0)
			(layer "B.Fab")
			(hide yes)
			(effects
				(font
					(size 1 1)
					(thickness 0.15)
				)
				(justify mirror)
			)
		)
		(property "License" "Apache-2.0"
			(at -28.555731 166.520369 0)
			(layer "B.Fab")
			(hide yes)
			(effects
				(font
					(size 1 1)
					(thickness 0.15)
				)
				(justify mirror)
			)
		)
		(property "MPN" "GRM035R60J475ME15D"
			(at -28.555731 166.520369 0)
			(layer "B.Fab")
			(hide yes)
			(effects
				(font
					(size 1 1)
					(thickness 0.15)
				)
				(justify mirror)
			)
		)
		(property "Manufacturer" "Murata"
			(at -28.555731 166.520369 0)
			(layer "B.Fab")
			(hide yes)
			(effects
				(font
					(size 1 1)
					(thickness 0.15)
				)
				(justify mirror)
			)
		)
		(property "Val" "4u7"
			(at -28.555731 166.520369 0)
			(layer "B.Fab")
			(hide yes)
			(effects
				(font
					(size 1 1)
					(thickness 0.15)
				)
				(justify mirror)
			)
		)
		(property "Voltage" ""
			(at -28.555731 166.520369 0)
			(layer "B.Fab")
			(hide yes)
			(effects
				(font
					(size 1 1)
					(thickness 0.15)
				)
				(justify mirror)
			)
		)
		(sheetname "FPGA supply")
		(sheetfile "fpga-supply.kicad_sch")
		(attr smd)
		(fp_poly
			(pts
				(xy -0.7 0.35) (xy 0.7 0.35) (xy 0.7 -0.35) (xy -0.7 -0.35)
			)
			(stroke
				(width 0.05)
				(type default)
			)
			(fill no)
			(layer "B.CrtYd")
		)
		(fp_poly
			(pts
				(xy 0.3 -0.15) (xy -0.301 -0.15) (xy -0.301 0.149) (xy 0.3 0.149)
			)
			(stroke
				(width 0.15)
				(type solid)
			)
			(fill no)
			(layer "B.Fab")
		)
		(pad "" smd roundrect
			(at -0.349 0.002 315)
			(size 0.318 0.36)
			(layers "B.Paste")
			(roundrect_rratio 0.25)
		)
		(pad "" smd roundrect
			(at 0.341 0.002 315)
			(size 0.318 0.36)
			(layers "B.Paste")
			(roundrect_rratio 0.25)
		)
		(pad "1" smd roundrect
			(at -0.321 0.002 315)
			(size 0.46 0.4)
			(layers "B.Cu" "B.Mask")
			(roundrect_rratio 0.25)
			(net 1 "GND")
			(pintype "passive")
		)
		(pad "2" smd roundrect
			(at 0.32 0.002 315)
			(size 0.46 0.4)
			(layers "B.Cu" "B.Mask")
			(roundrect_rratio 0.25)
			(net 8 "+1V2_MGTAVTT")
			(pintype "passive")
		)
	)
	(footprint "antmicro-footprints:NetTie-2_SMD_Pad0.127mm"
		(layer "B.Cu")
		(at 249.701 148.4 90)
		(descr "Net tie, 2 pin, 0.127mm  SMD pads")
		(tags "net tie")
		(property "Reference" "NT8"
			(at -0.128 1.345 270)
			(layer "B.SilkS")
			(hide yes)
			(effects
				(font
					(size 0.7 0.7)
					(thickness 0.15)
				)
				(justify left bottom mirror)
			)
		)
		(property "Value" "Net-Tie_2"
			(at 0 -1.199 270)
			(layer "B.Fab")
			(effects
				(font
					(size 0.7 0.7)
					(thickness 0.15)
				)
				(justify left bottom mirror)
			)
		)
		(property "Description" "Net tie, 2 pins"
			(at 0 0 90)
			(layer "F.Fab")
			(hide yes)
			(effects
				(font
					(size 1.27 1.27)
					(thickness 0.15)
				)
			)
		)
		(property "Author" "Antmicro"
			(at 398.101 -101.301 0)
			(layer "B.Fab")
			(hide yes)
			(effects
				(font
					(size 1 1)
					(thickness 0.15)
				)
				(justify mirror)
			)
		)
		(property "License" "Apache-2.0"
			(at 398.101 -101.301 0)
			(layer "B.Fab")
			(hide yes)
			(effects
				(font
					(size 1 1)
					(thickness 0.15)
				)
				(justify mirror)
			)
		)
		(property "MPN" ""
			(at 398.101 -101.301 0)
			(layer "B.Fab")
			(hide yes)
			(effects
				(font
					(size 1 1)
					(thickness 0.15)
				)
				(justify mirror)
			)
		)
		(property "Manufacturer" ""
			(at 398.101 -101.301 0)
			(layer "B.Fab")
			(hide yes)
			(effects
				(font
					(size 1 1)
					(thickness 0.15)
				)
				(justify mirror)
			)
		)
		(sheetname "FPGA Config")
		(sheetfile "fpga-config.kicad_sch")
		(attr exclude_from_pos_files)
		(net_tie_pad_groups "1, 2")
		(fp_poly
			(pts
				(xy -0.0635 0.0635) (xy 0.0625 0.0635) (xy 0.0625 -0.0635) (xy -0.0635 -0.0635)
			)
			(stroke
				(width 0)
				(type solid)
			)
			(fill yes)
			(layer "B.Cu")
		)
		(pad "1" smd roundrect
			(at -0.127 0 270)
			(size 0.127 0.127)
			(layers "B.Cu")
			(roundrect_rratio 0.5)
			(chamfer_ratio 0)
			(chamfer top_left bottom_left)
			(net 1317 "/SUP_MCU.PROGRAMB")
			(pinfunction "1")
			(pintype "passive")
		)
		(pad "2" smd roundrect
			(at 0.126 0 90)
			(size 0.127 0.127)
			(layers "B.Cu")
			(roundrect_rratio 0.5)
			(chamfer_ratio 0)
			(chamfer top_left bottom_left)
			(net 301 "/FPGA Config/PROGRAM_B")
			(pinfunction "2")
			(pintype "passive")
		)
	)
	(footprint "antmicro-footprints:C_0402_1005Metric"
		(layer "B.Cu")
		(at 206 139.5 180)
		(descr "Capacitor SMD 0402")
		(tags "capacitor SMD 0402")
		(property "Reference" "C29"
			(at -1.05 0.45 0)
			(layer "B.SilkS")
			(effects
				(font
					(size 0.7 0.7)
					(thickness 0.15)
				)
				(justify left bottom mirror)
			)
		)
		(property "Value" "C_100n_0402"
			(at 0 -1.169 0)
			(layer "B.Fab")
			(effects
				(font
					(size 0.7 0.7)
					(thickness 0.15)
				)
				(justify left bottom mirror)
			)
		)
		(property "Description" "SMD Multilayer Ceramic Capacitor, 0.1 µF, 50 V, 0402 [1005 Metric], ± 10%, X5R, GRM Series"
			(at 0 0 180)
			(layer "F.Fab")
			(hide yes)
			(effects
				(font
					(size 1.27 1.27)
					(thickness 0.15)
				)
			)
		)
		(property "Author" "Antmicro"
			(at 412 279 0)
			(layer "B.Fab")
			(hide yes)
			(effects
				(font
					(size 1 1)
					(thickness 0.15)
				)
				(justify mirror)
			)
		)
		(property "Dielectric" "X5R"
			(at 412 279 0)
			(layer "B.Fab")
			(hide yes)
			(effects
				(font
					(size 1 1)
					(thickness 0.15)
				)
				(justify mirror)
			)
		)
		(property "License" "Apache-2.0"
			(at 412 279 0)
			(layer "B.Fab")
			(hide yes)
			(effects
				(font
					(size 1 1)
					(thickness 0.15)
				)
				(justify mirror)
			)
		)
		(property "MPN" "GRM155R61H104KE14D"
			(at 412 279 0)
			(layer "B.Fab")
			(hide yes)
			(effects
				(font
					(size 1 1)
					(thickness 0.15)
				)
				(justify mirror)
			)
		)
		(property "Manufacturer" "Murata"
			(at 412 279 0)
			(layer "B.Fab")
			(hide yes)
			(effects
				(font
					(size 1 1)
					(thickness 0.15)
				)
				(justify mirror)
			)
		)
		(property "Val" "100n"
			(at 412 279 0)
			(layer "B.Fab")
			(hide yes)
			(effects
				(font
					(size 1 1)
					(thickness 0.15)
				)
				(justify mirror)
			)
		)
		(property "Voltage" "50V"
			(at 412 279 0)
			(layer "B.Fab")
			(hide yes)
			(effects
				(font
					(size 1 1)
					(thickness 0.15)
				)
				(justify mirror)
			)
		)
		(sheetname "FPGA Bank 12 & 13")
		(sheetfile "fpga-bank-12-13.kicad_sch")
		(attr smd)
		(fp_rect
			(start -0.925 0.47)
			(end 0.925 -0.47)
			(stroke
				(width 0.05)
				(type default)
			)
			(fill no)
			(layer "B.CrtYd")
		)
		(fp_line
			(start 0.504 0.25)
			(end 0.504 -0.248)
			(stroke
				(width 0.15)
				(type solid)
			)
			(layer "B.Fab")
		)
		(fp_line
			(start 0.504 -0.248)
			(end -0.494 -0.248)
			(stroke
				(width 0.15)
				(type solid)
			)
			(layer "B.Fab")
		)
		(fp_line
			(start -0.494 0.25)
			(end 0.504 0.25)
			(stroke
				(width 0.15)
				(type solid)
			)
			(layer "B.Fab")
		)
		(fp_line
			(start -0.494 -0.248)
			(end -0.494 0.25)
			(stroke
				(width 0.15)
				(type solid)
			)
			(layer "B.Fab")
		)
		(pad "1" smd roundrect
			(at -0.48 0 180)
			(size 0.59 0.64)
			(layers "B.Cu" "B.Mask" "B.Paste")
			(roundrect_rratio 0.25)
			(net 1 "GND")
			(pintype "passive")
		)
		(pad "2" smd roundrect
			(at 0.48 0 180)
			(size 0.59 0.64)
			(layers "B.Cu" "B.Mask" "B.Paste")
			(roundrect_rratio 0.25)
			(net 24 "+3V3")
			(pintype "passive")
		)
	)
)
